# SCM (Grand Teton) — schematic netlist excerpt (pin names and nets, part order shuffled) for the footprints in the layout excerpt that follows; sources: Cadence DE-HDL packaged netlist, KiCad conversion of 12092022_DA0F0TMDCD0_F0T_Management_Board_D_brd_V3_OCP.brd

PC221  Q_CAP  1UF 25V 10% X6S  pkg C0402  page 52 : A = P3V3_AUX_VCC ; B = GND
C119  Q_CAP  1UF 25V 10% X6S  pkg C0402  page 16 : A = P1V8_AUX ; B = GND

(kicad_pcb
	(version 20260206)
	(generator "pcbnew")
	(generator_version "10.0")
	(general
		(thickness 1.6)
		(legacy_teardrops no)
	)
	(paper "A4")
	(title_block
		(title "12092022_DA0F0TMDCD0_F0T_Management_Board_D_brd_V3_OCP.brd")
		(comment 1 "Grand Teton / footprints 573-574 of 1440")
	)
	(layers
		(0 "F.Cu" signal "TOP")
		(4 "In1.Cu" signal "GND")
		(6 "In2.Cu" signal "IN1")
		(8 "In3.Cu" signal "GND1")
		(10 "In4.Cu" signal "IN2")
		(12 "In5.Cu" signal "VCC")
		(14 "In6.Cu" signal "VCC1")
		(16 "In7.Cu" signal "IN3")
		(18 "In8.Cu" signal "GND2")
		(20 "In9.Cu" signal "IN4")
		(22 "In10.Cu" signal "GND3")
		(2 "B.Cu" signal "BOTTOM")
		(9 "F.Adhes" user "F.Adhesive")
		(11 "B.Adhes" user "B.Adhesive")
		(13 "F.Paste" user "Package Geometry/Pastemask Top")
		(15 "B.Paste" user "Package Geometry/Pastemask Bottom")
		(5 "F.SilkS" user "Ref Des/Silkscreen Top")
		(7 "B.SilkS" user "Ref Des/Silkscreen Bottom")
		(1 "F.Mask" user "Board Geometry/Soldermask Top")
		(3 "B.Mask" user "Board Geometry/Soldermask Bottom")
		(17 "Dwgs.User" user "User.Drawings")
		(19 "Cmts.User" user "User.Comments")
		(21 "Eco1.User" user "User.Eco1")
		(23 "Eco2.User" user "User.Eco2")
		(25 "Edge.Cuts" user "Board Geometry/Outline")
		(27 "Margin" user)
		(31 "F.CrtYd" user "Package Geometry/Place Bound Top")
		(29 "B.CrtYd" user "Package Geometry/Place Bound Bottom")
		(35 "F.Fab" user "Ref Des/Assembly Top")
		(33 "B.Fab" user "Ref Des/Assembly Bottom")
	)
	(footprint ""
		(layer "F.Cu")
		(at 69.265292 -35.261296 90)
		(property "Reference" "C119"
			(at 0 0 90)
			(layer "F.SilkS")
			(hide yes)
			(effects
				(font
					(size 1.27 1.27)
				)
			)
		)
		(property "Value" ""
			(at 0 0 90)
			(layer "F.Fab")
			(effects
				(font
					(size 1.27 1.27)
				)
			)
		)
		(duplicate_pad_numbers_are_jumpers no)
		(fp_line
			(start 0.7874 -0.4064)
			(end 0.7874 0.4064)
			(stroke
				(width 0.1524)
				(type default)
			)
			(layer "F.SilkS")
		)
		(fp_line
			(start -0.7874 -0.4064)
			(end 0.7874 -0.4064)
			(stroke
				(width 0.1524)
				(type default)
			)
			(layer "F.SilkS")
		)
		(fp_line
			(start 0.7874 0.4064)
			(end -0.7874 0.4064)
			(stroke
				(width 0.1524)
				(type default)
			)
			(layer "F.SilkS")
		)
		(fp_line
			(start -0.7874 0.4064)
			(end -0.7874 -0.4064)
			(stroke
				(width 0.1524)
				(type default)
			)
			(layer "F.SilkS")
		)
		(fp_line
			(start -0.12065 -0.305054)
			(end -0.12065 -0.2794)
			(stroke
				(width 0.1)
				(type default)
			)
			(layer "F.Fab")
		)
		(fp_line
			(start -0.67945 -0.305054)
			(end -0.12065 -0.305054)
			(stroke
				(width 0.1)
				(type default)
			)
			(layer "F.Fab")
		)
		(fp_line
			(start 0.67945 -0.3048)
			(end 0.67945 0.3048)
			(stroke
				(width 0.1)
				(type default)
			)
			(layer "F.Fab")
		)
		(fp_line
			(start 0.12065 -0.3048)
			(end 0.67945 -0.3048)
			(stroke
				(width 0.1)
				(type default)
			)
			(layer "F.Fab")
		)
		(fp_line
			(start 0.12065 -0.2794)
			(end 0.12065 -0.3048)
			(stroke
				(width 0.1)
				(type default)
			)
			(layer "F.Fab")
		)
		(fp_line
			(start -0.12065 -0.2794)
			(end 0.12065 -0.2794)
			(stroke
				(width 0.1)
				(type default)
			)
			(layer "F.Fab")
		)
		(fp_line
			(start 0.120396 0.2794)
			(end -0.12065 0.2794)
			(stroke
				(width 0.1)
				(type default)
			)
			(layer "F.Fab")
		)
		(fp_line
			(start -0.12065 0.2794)
			(end -0.12065 0.3048)
			(stroke
				(width 0.1)
				(type default)
			)
			(layer "F.Fab")
		)
		(fp_line
			(start 0.67945 0.3048)
			(end 0.120396 0.3048)
			(stroke
				(width 0.1)
				(type default)
			)
			(layer "F.Fab")
		)
		(fp_line
			(start 0.120396 0.3048)
			(end 0.120396 0.2794)
			(stroke
				(width 0.1)
				(type default)
			)
			(layer "F.Fab")
		)
		(fp_line
			(start -0.12065 0.3048)
			(end -0.67945 0.3048)
			(stroke
				(width 0.1)
				(type default)
			)
			(layer "F.Fab")
		)
		(fp_line
			(start -0.67945 0.3048)
			(end -0.67945 -0.305054)
			(stroke
				(width 0.1)
				(type default)
			)
			(layer "F.Fab")
		)
		(pad "1" smd circle
			(at -0.40005 0 90)
			(size 0 0)
			(layers "F.Cu" "F.Mask" "F.Paste")
			(net "P1V8_AUX")
		)
		(pad "2" smd circle
			(at 0.40005 0 90)
			(size 0 0)
			(layers "F.Cu" "F.Mask" "F.Paste")
			(net "GND")
		)
	)
	(footprint ""
		(layer "F.Cu")
		(at 5.13207 -64.550798 -90)
		(property "Reference" "PC221"
			(at 0 0 270)
			(layer "F.SilkS")
			(hide yes)
			(effects
				(font
					(size 1.27 1.27)
				)
			)
		)
		(property "Value" ""
			(at 0 0 270)
			(layer "F.Fab")
			(effects
				(font
					(size 1.27 1.27)
				)
			)
		)
		(duplicate_pad_numbers_are_jumpers no)
		(fp_line
			(start -0.7874 0.4064)
			(end -0.7874 -0.4064)
			(stroke
				(width 0.1524)
				(type default)
			)
			(layer "F.SilkS")
		)
		(fp_line
			(start 0.7874 0.4064)
			(end -0.7874 0.4064)
			(stroke
				(width 0.1524)
				(type default)
			)
			(layer "F.SilkS")
		)
		(fp_line
			(start -0.7874 -0.4064)
			(end 0.7874 -0.4064)
			(stroke
				(width 0.1524)
				(type default)
			)
			(layer "F.SilkS")
		)
		(fp_line
			(start 0.7874 -0.4064)
			(end 0.7874 0.4064)
			(stroke
				(width 0.1524)
				(type default)
			)
			(layer "F.SilkS")
		)
		(fp_line
			(start -0.67945 0.3048)
			(end -0.67945 -0.305054)
			(stroke
				(width 0.1)
				(type default)
			)
			(layer "F.Fab")
		)
		(fp_line
			(start -0.12065 0.3048)
			(end -0.67945 0.3048)
			(stroke
				(width 0.1)
				(type default)
			)
			(layer "F.Fab")
		)
		(fp_line
			(start 0.120396 0.3048)
			(end 0.120396 0.2794)
			(stroke
				(width 0.1)
				(type default)
			)
			(layer "F.Fab")
		)
		(fp_line
			(start 0.67945 0.3048)
			(end 0.120396 0.3048)
			(stroke
				(width 0.1)
				(type default)
			)
			(layer "F.Fab")
		)
		(fp_line
			(start -0.12065 0.2794)
			(end -0.12065 0.3048)
			(stroke
				(width 0.1)
				(type default)
			)
			(layer "F.Fab")
		)
		(fp_line
			(start 0.120396 0.2794)
			(end -0.12065 0.2794)
			(stroke
				(width 0.1)
				(type default)
			)
			(layer "F.Fab")
		)
		(fp_line
			(start -0.12065 -0.2794)
			(end 0.12065 -0.2794)
			(stroke
				(width 0.1)
				(type default)
			)
			(layer "F.Fab")
		)
		(fp_line
			(start 0.12065 -0.2794)
			(end 0.12065 -0.3048)
			(stroke
				(width 0.1)
				(type default)
			)
			(layer "F.Fab")
		)
		(fp_line
			(start 0.12065 -0.3048)
			(end 0.67945 -0.3048)
			(stroke
				(width 0.1)
				(type default)
			)
			(layer "F.Fab")
		)
		(fp_line
			(start 0.67945 -0.3048)
			(end 0.67945 0.3048)
			(stroke
				(width 0.1)
				(type default)
			)
			(layer "F.Fab")
		)
		(fp_line
			(start -0.67945 -0.305054)
			(end -0.12065 -0.305054)
			(stroke
				(width 0.1)
				(type default)
			)
			(layer "F.Fab")
		)
		(fp_line
			(start -0.12065 -0.305054)
			(end -0.12065 -0.2794)
			(stroke
				(width 0.1)
				(type default)
			)
			(layer "F.Fab")
		)
		(pad "1" smd circle
			(at -0.40005 0 270)
			(size 0 0)
			(layers "F.Cu" "F.Mask" "F.Paste")
			(net "P3V3_AUX_VCC")
		)
		(pad "2" smd circle
			(at 0.40005 0 270)
			(size 0 0)
			(layers "F.Cu" "F.Mask" "F.Paste")
			(net "GND")
		)
	)
)
